# T6G (Grand Teton) — schematic netlist excerpt (pin names and nets, part order shuffled) for the footprints in the layout excerpt that follows; sources: Cadence DE-HDL packaged netlist, KiCad conversion of 04192023_DAF0TMB3IC0_F0TG_MB_C_brd_V02_OCP.brd

R3453  Q_RES  100K 1% EMPTY  pkg 0402LF  page 128 : A = P3V3_AUX ; B = GPU_FPGA_BOOT_EN_BUF_R
PR507  Q_RES  1.5 1% EMPTY  pkg 0402LF  page 201 : A = SW_PVDDCR_CPU1_P0_SW2_RC ; B = GND

(kicad_pcb
	(version 20260206)
	(generator "pcbnew")
	(generator_version "10.0")
	(general
		(thickness 1.6)
		(legacy_teardrops no)
	)
	(paper "A4")
	(title_block
		(title "04192023_DAF0TMB3IC0_F0TG_MB_C_brd_V02_OCP.brd")
		(comment 1 "Grand Teton / footprints 1656-1657 of 8354")
	)
	(layers
		(0 "F.Cu" signal "TOP")
		(4 "In1.Cu" signal "GND")
		(6 "In2.Cu" signal "IN1")
		(8 "In3.Cu" signal "GND1")
		(10 "In4.Cu" signal "IN2")
		(12 "In5.Cu" signal "GND2")
		(14 "In6.Cu" signal "IN3")
		(16 "In7.Cu" signal "GND3")
		(18 "In8.Cu" signal "VCC")
		(20 "In9.Cu" signal "VCC1")
		(22 "In10.Cu" signal "GND4")
		(24 "In11.Cu" signal "IN4")
		(26 "In12.Cu" signal "GND5")
		(28 "In13.Cu" signal "IN5")
		(30 "In14.Cu" signal "GND6")
		(32 "In15.Cu" signal "IN6")
		(34 "In16.Cu" signal "GND7")
		(2 "B.Cu" signal "BOTTOM")
		(9 "F.Adhes" user "F.Adhesive")
		(11 "B.Adhes" user "B.Adhesive")
		(13 "F.Paste" user "Package Geometry/Pastemask Top")
		(15 "B.Paste" user "Package Geometry/Pastemask Bottom")
		(5 "F.SilkS" user "Ref Des/Silkscreen Top")
		(7 "B.SilkS" user "Ref Des/Silkscreen Bottom")
		(1 "F.Mask" user "Board Geometry/Soldermask Top")
		(3 "B.Mask" user "Board Geometry/Soldermask Bottom")
		(17 "Dwgs.User" user "User.Drawings")
		(19 "Cmts.User" user "User.Comments")
		(21 "Eco1.User" user "User.Eco1")
		(23 "Eco2.User" user "User.Eco2")
		(25 "Edge.Cuts" user "Board Geometry/Outline")
		(27 "Margin" user)
		(31 "F.CrtYd" user "Package Geometry/Place Bound Top")
		(29 "B.CrtYd" user "Package Geometry/Place Bound Bottom")
		(35 "F.Fab" user "Ref Des/Assembly Top")
		(33 "B.Fab" user "Ref Des/Assembly Bottom")
	)
	(footprint ""
		(layer "F.Cu")
		(at 120.396 -424.688)
		(property "Reference" "R3453"
			(at 0 0 0)
			(layer "F.SilkS")
			(hide yes)
			(effects
				(font
					(size 1.27 1.27)
				)
			)
		)
		(property "Value" ""
			(at 0 0 0)
			(layer "F.Fab")
			(effects
				(font
					(size 1.27 1.27)
				)
			)
		)
		(duplicate_pad_numbers_are_jumpers no)
		(fp_line
			(start -0.7874 -0.4064)
			(end 0.7874 -0.4064)
			(stroke
				(width 0.1524)
				(type default)
			)
			(layer "F.SilkS")
		)
		(fp_line
			(start -0.7874 0.4064)
			(end -0.7874 -0.4064)
			(stroke
				(width 0.1524)
				(type default)
			)
			(layer "F.SilkS")
		)
		(fp_line
			(start 0.7874 -0.4064)
			(end 0.7874 0.4064)
			(stroke
				(width 0.1524)
				(type default)
			)
			(layer "F.SilkS")
		)
		(fp_line
			(start 0.7874 0.4064)
			(end -0.7874 0.4064)
			(stroke
				(width 0.1524)
				(type default)
			)
			(layer "F.SilkS")
		)
		(fp_line
			(start -0.67945 -0.305054)
			(end -0.12065 -0.305054)
			(stroke
				(width 0.1)
				(type default)
			)
			(layer "F.Fab")
		)
		(fp_line
			(start -0.67945 0.3048)
			(end -0.67945 -0.305054)
			(stroke
				(width 0.1)
				(type default)
			)
			(layer "F.Fab")
		)
		(fp_line
			(start -0.12065 -0.305054)
			(end -0.12065 -0.2794)
			(stroke
				(width 0.1)
				(type default)
			)
			(layer "F.Fab")
		)
		(fp_line
			(start -0.12065 -0.2794)
			(end 0.12065 -0.2794)
			(stroke
				(width 0.1)
				(type default)
			)
			(layer "F.Fab")
		)
		(fp_line
			(start -0.12065 0.2794)
			(end -0.12065 0.3048)
			(stroke
				(width 0.1)
				(type default)
			)
			(layer "F.Fab")
		)
		(fp_line
			(start -0.12065 0.3048)
			(end -0.67945 0.3048)
			(stroke
				(width 0.1)
				(type default)
			)
			(layer "F.Fab")
		)
		(fp_line
			(start 0.120396 0.2794)
			(end -0.12065 0.2794)
			(stroke
				(width 0.1)
				(type default)
			)
			(layer "F.Fab")
		)
		(fp_line
			(start 0.120396 0.3048)
			(end 0.120396 0.2794)
			(stroke
				(width 0.1)
				(type default)
			)
			(layer "F.Fab")
		)
		(fp_line
			(start 0.12065 -0.3048)
			(end 0.67945 -0.3048)
			(stroke
				(width 0.1)
				(type default)
			)
			(layer "F.Fab")
		)
		(fp_line
			(start 0.12065 -0.2794)
			(end 0.12065 -0.3048)
			(stroke
				(width 0.1)
				(type default)
			)
			(layer "F.Fab")
		)
		(fp_line
			(start 0.67945 -0.3048)
			(end 0.67945 0.3048)
			(stroke
				(width 0.1)
				(type default)
			)
			(layer "F.Fab")
		)
		(fp_line
			(start 0.67945 0.3048)
			(end 0.120396 0.3048)
			(stroke
				(width 0.1)
				(type default)
			)
			(layer "F.Fab")
		)
		(pad "1" smd circle
			(at -0.40005 0)
			(size 0 0)
			(layers "F.Cu" "F.Mask" "F.Paste")
			(net "P3V3_AUX")
		)
		(pad "2" smd circle
			(at 0.40005 0)
			(size 0 0)
			(layers "F.Cu" "F.Mask" "F.Paste")
			(net "GPU_FPGA_BOOT_EN_BUF_R")
		)
	)
	(footprint ""
		(layer "F.Cu")
		(at 323.024246 -333.253842 90)
		(property "Reference" "PR507"
			(at 0 0 90)
			(layer "F.SilkS")
			(hide yes)
			(effects
				(font
					(size 1.27 1.27)
				)
			)
		)
		(property "Value" ""
			(at 0 0 90)
			(layer "F.Fab")
			(effects
				(font
					(size 1.27 1.27)
				)
			)
		)
		(duplicate_pad_numbers_are_jumpers no)
		(fp_line
			(start 0.7874 -0.4064)
			(end 0.7874 0.4064)
			(stroke
				(width 0.1524)
				(type default)
			)
			(layer "F.SilkS")
		)
		(fp_line
			(start -0.7874 -0.4064)
			(end 0.7874 -0.4064)
			(stroke
				(width 0.1524)
				(type default)
			)
			(layer "F.SilkS")
		)
		(fp_line
			(start 0.7874 0.4064)
			(end -0.7874 0.4064)
			(stroke
				(width 0.1524)
				(type default)
			)
			(layer "F.SilkS")
		)
		(fp_line
			(start -0.7874 0.4064)
			(end -0.7874 -0.4064)
			(stroke
				(width 0.1524)
				(type default)
			)
			(layer "F.SilkS")
		)
		(fp_line
			(start -0.12065 -0.305054)
			(end -0.12065 -0.2794)
			(stroke
				(width 0.1)
				(type default)
			)
			(layer "F.Fab")
		)
		(fp_line
			(start -0.67945 -0.305054)
			(end -0.12065 -0.305054)
			(stroke
				(width 0.1)
				(type default)
			)
			(layer "F.Fab")
		)
		(fp_line
			(start 0.67945 -0.3048)
			(end 0.67945 0.3048)
			(stroke
				(width 0.1)
				(type default)
			)
			(layer "F.Fab")
		)
		(fp_line
			(start 0.12065 -0.3048)
			(end 0.67945 -0.3048)
			(stroke
				(width 0.1)
				(type default)
			)
			(layer "F.Fab")
		)
		(fp_line
			(start 0.12065 -0.2794)
			(end 0.12065 -0.3048)
			(stroke
				(width 0.1)
				(type default)
			)
			(layer "F.Fab")
		)
		(fp_line
			(start -0.12065 -0.2794)
			(end 0.12065 -0.2794)
			(stroke
				(width 0.1)
				(type default)
			)
			(layer "F.Fab")
		)
		(fp_line
			(start 0.120396 0.2794)
			(end -0.12065 0.2794)
			(stroke
				(width 0.1)
				(type default)
			)
			(layer "F.Fab")
		)
		(fp_line
			(start -0.12065 0.2794)
			(end -0.12065 0.3048)
			(stroke
				(width 0.1)
				(type default)
			)
			(layer "F.Fab")
		)
		(fp_line
			(start 0.67945 0.3048)
			(end 0.120396 0.3048)
			(stroke
				(width 0.1)
				(type default)
			)
			(layer "F.Fab")
		)
		(fp_line
			(start 0.120396 0.3048)
			(end 0.120396 0.2794)
			(stroke
				(width 0.1)
				(type default)
			)
			(layer "F.Fab")
		)
		(fp_line
			(start -0.12065 0.3048)
			(end -0.67945 0.3048)
			(stroke
				(width 0.1)
				(type default)
			)
			(layer "F.Fab")
		)
		(fp_line
			(start -0.67945 0.3048)
			(end -0.67945 -0.305054)
			(stroke
				(width 0.1)
				(type default)
			)
			(layer "F.Fab")
		)
		(pad "1" smd circle
			(at -0.40005 0 90)
			(size 0 0)
			(layers "F.Cu" "F.Mask" "F.Paste")
			(net "SW_PVDDCR_CPU1_P0_SW2_RC")
		)
		(pad "2" smd circle
			(at 0.40005 0 90)
			(size 0 0)
			(layers "F.Cu" "F.Mask" "F.Paste")
			(net "GND")
		)
	)
)
